(kicad_pcb
	(version 20260206)
	(generator "pcbnew")
	(generator_version "10.0")
	(general
		(thickness 1.6)
		(legacy_teardrops no)
	)
	(paper "A4")
	(title_block
		(title "Bryce Canyon_F.DPB_16315-1-OCP.brd")
		(comment 1 "Bryce Canyon / footprints 1379-1384 of 2223")
	)
	(layers
		(0 "F.Cu" signal "TOP")
		(4 "In1.Cu" signal "L2GND")
		(6 "In2.Cu" signal "L3")
		(8 "In3.Cu" signal "L4GND")
		(10 "In4.Cu" signal "L5")
		(12 "In5.Cu" signal "L6VCC")
		(14 "In6.Cu" signal "L7VCC")
		(16 "In7.Cu" signal "L8")
		(18 "In8.Cu" signal "L9GND")
		(20 "In9.Cu" signal "L10")
		(22 "In10.Cu" signal "L11GND")
		(2 "B.Cu" signal "BOTTOM")
		(9 "F.Adhes" user "F.Adhesive")
		(11 "B.Adhes" user "B.Adhesive")
		(13 "F.Paste" user "Package Geometry/Pastemask Top")
		(15 "B.Paste" user "Package Geometry/Pastemask Bottom")
		(5 "F.SilkS" user "Ref Des/Silkscreen Top")
		(7 "B.SilkS" user "Ref Des/Silkscreen Bottom")
		(1 "F.Mask" user "Board Geometry/Soldermask Top")
		(3 "B.Mask" user "Board Geometry/Soldermask Bottom")
		(17 "Dwgs.User" user "User.Drawings")
		(19 "Cmts.User" user "User.Comments")
		(21 "Eco1.User" user "User.Eco1")
		(23 "Eco2.User" user "User.Eco2")
		(25 "Edge.Cuts" user "Board Geometry/Outline")
		(27 "Margin" user)
		(31 "F.CrtYd" user "Package Geometry/Place Bound Top")
		(29 "B.CrtYd" user "Package Geometry/Place Bound Bottom")
		(35 "F.Fab" user "Ref Des/Assembly Top")
		(33 "B.Fab" user "Ref Des/Assembly Bottom")
	)
	(footprint ""
		(layer "F.Cu")
		(at 238.252 -382.1938)
		(property "Reference" "C586"
			(at 0 0 0)
			(layer "F.SilkS")
			(hide yes)
			(effects
				(font
					(size 1.27 1.27)
				)
			)
		)
		(property "Value" "SCD1U16V2KX-3GP"
			(at 1.1811 -2.7051 0)
			(unlocked yes)
			(layer "F.Fab")
			(hide yes)
			(effects
				(font
					(size 1.016 1.016)
					(thickness 0.1524)
				)
			)
		)
		(property "Device Type" "C402H22"
			(at 1.1811 -4.2291 0)
			(unlocked yes)
			(layer "F.Fab")
			(hide yes)
			(effects
				(font
					(size 1.016 1.016)
					(thickness 0.1524)
				)
			)
		)
		(duplicate_pad_numbers_are_jumpers no)
		(fp_rect
			(start -0.4318 0.9525)
			(end 0.4318 -0.9525)
			(stroke
				(width 0)
				(type default)
			)
			(fill no)
			(layer "F.CrtYd")
		)
		(fp_rect
			(start -0.4318 0.9525)
			(end 0.4318 -0.9525)
			(stroke
				(width 0)
				(type default)
			)
			(fill no)
			(layer "F.Fab")
		)
		(pad "1" smd custom
			(at 0 -0.4445)
			(size 0.1524 0.1524)
			(layers "F.Cu" "F.Mask" "F.Paste")
			(net "MB3_CM_VOUT_R")
			(options
				(clearance outline)
				(anchor circle)
			)
			(primitives
				(gr_poly
					(pts
						(arc
							(start 0.3048 -0.2032)
							(mid 0.275042 -0.275042)
							(end 0.2032 -0.3048)
						)
						(arc
							(start -0.2032 -0.3048)
							(mid -0.275042 -0.275042)
							(end -0.3048 -0.2032)
						)
						(arc
							(start -0.3048 0.2032)
							(mid -0.275042 0.275042)
							(end -0.2032 0.3048)
						)
						(arc
							(start 0.2032 0.3048)
							(mid 0.275042 0.275042)
							(end 0.3048 0.2032)
						)
					)
					(width 0)
					(fill yes)
				)
			)
		)
		(pad "2" smd custom
			(at 0 0.4445)
			(size 0.1524 0.1524)
			(layers "F.Cu" "F.Mask" "F.Paste")
			(net "AGND_CURRENT_DPB")
			(options
				(clearance outline)
				(anchor circle)
			)
			(primitives
				(gr_poly
					(pts
						(arc
							(start 0.3048 -0.2032)
							(mid 0.275042 -0.275042)
							(end 0.2032 -0.3048)
						)
						(arc
							(start -0.2032 -0.3048)
							(mid -0.275042 -0.275042)
							(end -0.3048 -0.2032)
						)
						(arc
							(start -0.3048 0.2032)
							(mid -0.275042 0.275042)
							(end -0.2032 0.3048)
						)
						(arc
							(start 0.2032 0.3048)
							(mid 0.275042 0.275042)
							(end 0.3048 0.2032)
						)
					)
					(width 0)
					(fill yes)
				)
			)
		)
	)
	(footprint ""
		(layer "F.Cu")
		(at 54.546246 -48.554894 90)
		(property "Reference" "R717"
			(at 0 0 90)
			(layer "F.SilkS")
			(hide yes)
			(effects
				(font
					(size 1.27 1.27)
				)
			)
		)
		(property "Value" "4K7R2J-2-GP"
			(at 0.064008 -3.993896 90)
			(unlocked yes)
			(layer "F.Fab")
			(hide yes)
			(effects
				(font
					(size 1.016 1.016)
					(thickness 0.1524)
				)
			)
		)
		(property "Device Type" "R402H16"
			(at 0.064008 -5.517896 90)
			(unlocked yes)
			(layer "F.Fab")
			(hide yes)
			(effects
				(font
					(size 1.016 1.016)
					(thickness 0.1524)
				)
			)
		)
		(duplicate_pad_numbers_are_jumpers no)
		(fp_line
			(start 0.508 -0.9398)
			(end -0.508 -0.9398)
			(stroke
				(width 0.1524)
				(type default)
			)
			(layer "F.SilkS")
		)
		(fp_line
			(start -0.508 -0.9398)
			(end -0.508 0.9398)
			(stroke
				(width 0.1524)
				(type default)
			)
			(layer "F.SilkS")
		)
		(fp_rect
			(start -0.508 0.9398)
			(end 0.508 -0.9398)
			(stroke
				(width 0)
				(type default)
			)
			(fill no)
			(layer "F.CrtYd")
		)
		(fp_rect
			(start -0.508 0.9398)
			(end 0.508 -0.9398)
			(stroke
				(width 0)
				(type default)
			)
			(fill no)
			(layer "F.Fab")
		)
		(pad "1" smd custom
			(at 0 -0.4445 90)
			(size 0.1397 0.1397)
			(layers "F.Cu" "F.Mask" "F.Paste")
			(net "SW_PWR_R_HDD25")
			(options
				(clearance outline)
				(anchor circle)
			)
			(primitives
				(gr_poly
					(pts
						(arc
							(start -0.1778 -0.2794)
							(mid -0.249642 -0.249642)
							(end -0.2794 -0.1778)
						)
						(arc
							(start -0.2794 0.1778)
							(mid -0.249642 0.249642)
							(end -0.1778 0.2794)
						)
						(arc
							(start 0.1778 0.2794)
							(mid 0.249642 0.249642)
							(end 0.2794 0.1778)
						)
						(arc
							(start 0.2794 -0.1778)
							(mid 0.249642 -0.249642)
							(end 0.1778 -0.2794)
						)
					)
					(width 0)
					(fill yes)
				)
			)
		)
		(pad "2" smd custom
			(at 0 0.4445 90)
			(size 0.1397 0.1397)
			(layers "F.Cu" "F.Mask" "F.Paste")
			(net "GND")
			(options
				(clearance outline)
				(anchor circle)
			)
			(primitives
				(gr_poly
					(pts
						(arc
							(start -0.1778 -0.2794)
							(mid -0.249642 -0.249642)
							(end -0.2794 -0.1778)
						)
						(arc
							(start -0.2794 0.1778)
							(mid -0.249642 0.249642)
							(end -0.1778 0.2794)
						)
						(arc
							(start 0.1778 0.2794)
							(mid 0.249642 0.249642)
							(end 0.2794 0.1778)
						)
						(arc
							(start 0.2794 -0.1778)
							(mid 0.249642 -0.249642)
							(end 0.1778 -0.2794)
						)
					)
					(width 0)
					(fill yes)
				)
			)
		)
	)
	(footprint ""
		(layer "F.Cu")
		(at 80.63357 -17.368266 90)
		(property "Reference" "R39"
			(at 0 0 90)
			(layer "F.SilkS")
			(hide yes)
			(effects
				(font
					(size 1.27 1.27)
				)
			)
		)
		(property "Value" "4K7R2F-GP"
			(at 0.064008 -3.993896 90)
			(unlocked yes)
			(layer "F.Fab")
			(hide yes)
			(effects
				(font
					(size 1.016 1.016)
					(thickness 0.1524)
				)
			)
		)
		(property "Device Type" "R402H16"
			(at 0.064008 -5.517896 90)
			(unlocked yes)
			(layer "F.Fab")
			(hide yes)
			(effects
				(font
					(size 1.016 1.016)
					(thickness 0.1524)
				)
			)
		)
		(duplicate_pad_numbers_are_jumpers no)
		(fp_line
			(start 0.508 -0.9398)
			(end -0.508 -0.9398)
			(stroke
				(width 0.1524)
				(type default)
			)
			(layer "F.SilkS")
		)
		(fp_line
			(start -0.508 -0.9398)
			(end -0.508 0.9398)
			(stroke
				(width 0.1524)
				(type default)
			)
			(layer "F.SilkS")
		)
		(fp_rect
			(start -0.508 0.9398)
			(end 0.508 -0.9398)
			(stroke
				(width 0)
				(type default)
			)
			(fill no)
			(layer "F.CrtYd")
		)
		(fp_rect
			(start -0.508 0.9398)
			(end 0.508 -0.9398)
			(stroke
				(width 0)
				(type default)
			)
			(fill no)
			(layer "F.Fab")
		)
		(pad "1" smd custom
			(at 0 -0.4445 90)
			(size 0.1397 0.1397)
			(layers "F.Cu" "F.Mask" "F.Paste")
			(net "P3V3_STBY_A")
			(options
				(clearance outline)
				(anchor circle)
			)
			(primitives
				(gr_poly
					(pts
						(arc
							(start -0.1778 -0.2794)
							(mid -0.249642 -0.249642)
							(end -0.2794 -0.1778)
						)
						(arc
							(start -0.2794 0.1778)
							(mid -0.249642 0.249642)
							(end -0.1778 0.2794)
						)
						(arc
							(start 0.1778 0.2794)
							(mid 0.249642 0.249642)
							(end 0.2794 0.1778)
						)
						(arc
							(start 0.2794 -0.1778)
							(mid 0.249642 -0.249642)
							(end 0.1778 -0.2794)
						)
					)
					(width 0)
					(fill yes)
				)
			)
		)
		(pad "2" smd custom
			(at 0 0.4445 90)
			(size 0.1397 0.1397)
			(layers "F.Cu" "F.Mask" "F.Paste")
			(net "IO_EXP10_A1")
			(options
				(clearance outline)
				(anchor circle)
			)
			(primitives
				(gr_poly
					(pts
						(arc
							(start -0.1778 -0.2794)
							(mid -0.249642 -0.249642)
							(end -0.2794 -0.1778)
						)
						(arc
							(start -0.2794 0.1778)
							(mid -0.249642 0.249642)
							(end -0.1778 0.2794)
						)
						(arc
							(start 0.1778 0.2794)
							(mid 0.249642 0.249642)
							(end 0.2794 0.1778)
						)
						(arc
							(start 0.2794 -0.1778)
							(mid 0.249642 -0.249642)
							(end 0.1778 -0.2794)
						)
					)
					(width 0)
					(fill yes)
				)
			)
		)
	)
	(footprint ""
		(layer "F.Cu")
		(at 106.281728 -130.260598 -90)
		(property "Reference" "R516"
			(at 0 0 270)
			(layer "F.SilkS")
			(hide yes)
			(effects
				(font
					(size 1.27 1.27)
				)
			)
		)
		(property "Value" "4K7R2J-2-GP"
			(at 0.064008 -3.993896 270)
			(unlocked yes)
			(layer "F.Fab")
			(hide yes)
			(effects
				(font
					(size 1.016 1.016)
					(thickness 0.1524)
				)
			)
		)
		(property "Device Type" "R402H16"
			(at 0.064008 -5.517896 270)
			(unlocked yes)
			(layer "F.Fab")
			(hide yes)
			(effects
				(font
					(size 1.016 1.016)
					(thickness 0.1524)
				)
			)
		)
		(duplicate_pad_numbers_are_jumpers no)
		(fp_line
			(start -0.508 -0.9398)
			(end -0.508 0.9398)
			(stroke
				(width 0.1524)
				(type default)
			)
			(layer "F.SilkS")
		)
		(fp_line
			(start 0.508 -0.9398)
			(end -0.508 -0.9398)
			(stroke
				(width 0.1524)
				(type default)
			)
			(layer "F.SilkS")
		)
		(fp_rect
			(start -0.508 0.9398)
			(end 0.508 -0.9398)
			(stroke
				(width 0)
				(type default)
			)
			(fill no)
			(layer "F.CrtYd")
		)
		(fp_rect
			(start -0.508 0.9398)
			(end 0.508 -0.9398)
			(stroke
				(width 0)
				(type default)
			)
			(fill no)
			(layer "F.Fab")
		)
		(pad "1" smd custom
			(at 0 -0.4445 270)
			(size 0.1397 0.1397)
			(layers "F.Cu" "F.Mask" "F.Paste")
			(net "DRIVE_A_15_ACT")
			(options
				(clearance outline)
				(anchor circle)
			)
			(primitives
				(gr_poly
					(pts
						(arc
							(start -0.1778 -0.2794)
							(mid -0.249642 -0.249642)
							(end -0.2794 -0.1778)
						)
						(arc
							(start -0.2794 0.1778)
							(mid -0.249642 0.249642)
							(end -0.1778 0.2794)
						)
						(arc
							(start 0.1778 0.2794)
							(mid 0.249642 0.249642)
							(end 0.2794 0.1778)
						)
						(arc
							(start 0.2794 -0.1778)
							(mid 0.249642 -0.249642)
							(end 0.1778 -0.2794)
						)
					)
					(width 0)
					(fill yes)
				)
			)
		)
		(pad "2" smd custom
			(at 0 0.4445 270)
			(size 0.1397 0.1397)
			(layers "F.Cu" "F.Mask" "F.Paste")
			(net "GND")
			(options
				(clearance outline)
				(anchor circle)
			)
			(primitives
				(gr_poly
					(pts
						(arc
							(start -0.1778 -0.2794)
							(mid -0.249642 -0.249642)
							(end -0.2794 -0.1778)
						)
						(arc
							(start -0.2794 0.1778)
							(mid -0.249642 0.249642)
							(end -0.1778 0.2794)
						)
						(arc
							(start 0.1778 0.2794)
							(mid 0.249642 0.249642)
							(end 0.2794 0.1778)
						)
						(arc
							(start 0.2794 -0.1778)
							(mid 0.249642 -0.249642)
							(end 0.1778 -0.2794)
						)
					)
					(width 0)
					(fill yes)
				)
			)
		)
	)
	(footprint ""
		(layer "F.Cu")
		(at 240.000028 17.799812)
		(property "Reference" ""
			(at 0 0 0)
			(layer "F.SilkS")
			(hide yes)
			(effects
				(font
					(size 1.27 1.27)
				)
			)
		)
		(property "Value" "*"
			(at 8.305292 -3.58013 0)
			(unlocked yes)
			(layer "F.Fab")
			(hide yes)
			(effects
				(font
					(size 1.016 1.016)
					(thickness 0.1524)
				)
			)
		)
		(duplicate_pad_numbers_are_jumpers no)
		(fp_poly
			(pts
				(arc
					(start 6.80466 0)
					(mid 0 6.80466)
					(end -6.804914 0)
				)
				(arc
					(start -6.804914 -5.999988)
					(mid -2.856487 -12.176179)
					(end 4.406646 -11.18489)
				)
				(arc
					(start 4.406646 -11.18489)
					(mid 4.994737 -9.371935)
					(end 6.45668 -8.149082)
				)
				(arc
					(start 6.45668 -8.149082)
					(mid 6.717129 -7.088791)
					(end 6.80466 -6.000496)
				)
			)
			(stroke
				(width 0)
				(type default)
			)
			(fill no)
			(layer "B.CrtYd")
		)
		(fp_poly
			(pts
				(arc
					(start 6.80466 0)
					(mid 0 6.80466)
					(end -6.804914 0)
				)
				(arc
					(start -6.804914 -5.999988)
					(mid -2.856487 -12.176179)
					(end 4.406646 -11.18489)
				)
				(arc
					(start 4.406646 -11.18489)
					(mid 4.994737 -9.371935)
					(end 6.45668 -8.149082)
				)
				(arc
					(start 6.45668 -8.149082)
					(mid 6.7171 -7.088787)
					(end 6.80466 -6.000496)
				)
			)
			(stroke
				(width 0)
				(type default)
			)
			(fill no)
			(layer "F.CrtYd")
		)
		(fp_poly
			(pts
				(arc
					(start 6.80466 0)
					(mid 0 6.80466)
					(end -6.804914 0)
				)
				(arc
					(start -6.804914 -5.999988)
					(mid -2.856487 -12.176179)
					(end 4.406646 -11.18489)
				)
				(arc
					(start 4.406646 -11.18489)
					(mid 4.994737 -9.371935)
					(end 6.45668 -8.149082)
				)
				(arc
					(start 6.45668 -8.149082)
					(mid 6.7171 -7.088787)
					(end 6.80466 -6.000496)
				)
			)
			(stroke
				(width 0)
				(type default)
			)
			(fill no)
			(layer "B.Fab")
		)
		(fp_poly
			(pts
				(arc
					(start 6.80466 0)
					(mid 0 6.80466)
					(end -6.804914 0)
				)
				(arc
					(start -6.804914 -5.999988)
					(mid -2.856487 -12.176179)
					(end 4.406646 -11.18489)
				)
				(arc
					(start 4.406646 -11.18489)
					(mid 4.994737 -9.371935)
					(end 6.45668 -8.149082)
				)
				(arc
					(start 6.45668 -8.149082)
					(mid 6.7171 -7.088787)
					(end 6.80466 -6.000496)
				)
			)
			(stroke
				(width 0)
				(type default)
			)
			(fill no)
			(layer "F.Fab")
		)
		(pad "1" thru_hole custom
			(at 0 0)
			(size 3.249993 3.249993)
			(drill 0.0254)
			(layers "*.Cu" "*.Mask")
			(remove_unused_layers no)
			(net "Net_20")
			(clearance -0.491998)
			(thermal_gap 0.152146)
			(options
				(clearance outline)
				(anchor circle)
			)
			(primitives
				(gr_poly
					(pts
						(arc
							(start 6.207506 -4.92887)
							(mid 6.426581 -3.975471)
							(end 6.500114 -2.999994)
						)
						(arc
							(start 6.500114 2.999994)
							(mid 0.000254 9.499854)
							(end -6.49986 2.999994)
						)
						(arc
							(start -6.49986 -2.999994)
							(mid -2.787263 -8.871905)
							(end 4.109466 -8.036052)
						)
						(arc
							(start 4.109466 -8.036052)
							(mid 4.742316 -6.201459)
							(end 6.207506 -4.92887)
						)
					)
					(width 0)
					(fill yes)
				)
			)
			(padstack
				(mode front_inner_back)
				(layer "Inner"
					(shape custom)
					(size 2.928042 2.928042)
					(options
						(anchor circle)
					)
					(primitives
						(gr_poly
							(pts
								(arc
									(start 4.827016 -1.740154)
									(mid 0.000326 7.43067)
									(end -4.826762 -1.740154)
								)
								(arc
									(start -4.826762 -1.740154)
									(mid -3.703196 -3.586115)
									(end -2.789174 -5.544312)
								)
								(arc
									(start -2.789174 -5.544312)
									(mid 0.000254 -7.430741)
									(end 2.789682 -5.544312)
								)
								(arc
									(start 2.789682 -5.544312)
									(mid 3.703559 -3.586111)
									(end 4.827016 -1.740154)
								)
							)
							(width 0)
							(fill yes)
						)
					)
					(clearance 0.152146)
				)
				(layer "B.Cu"
					(shape custom)
					(size 3.249993 3.249993)
					(options
						(anchor circle)
					)
					(primitives
						(gr_poly
							(pts
								(arc
									(start 6.207506 -4.92887)
									(mid 6.426581 -3.975471)
									(end 6.500114 -2.999994)
								)
								(arc
									(start 6.500114 2.999994)
									(mid 0.000254 9.499854)
									(end -6.49986 2.999994)
								)
								(arc
									(start -6.49986 -2.999994)
									(mid -2.787263 -8.871905)
									(end 4.109466 -8.036052)
								)
								(arc
									(start 4.109466 -8.036052)
									(mid 4.742316 -6.201459)
									(end 6.207506 -4.92887)
								)
							)
							(width 0)
							(fill yes)
						)
					)
					(clearance -0.491998)
				)
			)
		)
		(zone
			(layers "F.Cu" "B.Cu" "In1.Cu" "In2.Cu" "In3.Cu" "In4.Cu" "In5.Cu" "In6.Cu"
				"In7.Cu" "In8.Cu" "In9.Cu" "In10.Cu"
			)
			(hatch none 0.5)
			(connect_pads
				(clearance 0)
			)
			(min_thickness 0.25)
			(keepout
				(tracks not_allowed)
				(vias allowed)
				(pads allowed)
				(copperpour not_allowed)
				(footprints allowed)
			)
			(placement
				(enabled no)
				(sheetname "")
			)
			(fill
				(thermal_gap 0.5)
				(thermal_bridge_width 0.5)
				(island_removal_mode 0)
			)
			(polygon
				(pts
					(arc
						(start 246.499888 17.799812)
						(mid 240.000028 24.299672)
						(end 233.499914 17.799812)
					)
					(arc
						(start 233.499914 11.799824)
						(mid 237.212511 5.927913)
						(end 244.10924 6.763766)
					)
					(arc
						(start 244.10924 6.763766)
						(mid 244.74209 8.598359)
						(end 246.20728 9.870948)
					)
					(arc
						(start 246.20728 9.870948)
						(mid 246.426317 10.824095)
						(end 246.499888 11.799316)
					)
				)
			)
		)
	)
	(footprint ""
		(layer "F.Cu")
		(at 300.20006 -138.205718)
		(property "Reference" ""
			(at 0 0 0)
			(layer "F.SilkS")
			(hide yes)
			(effects
				(font
					(size 1.27 1.27)
				)
			)
		)
		(property "Value" "*"
			(at -8.398764 -8.057642 0)
			(unlocked yes)
			(layer "F.Fab")
			(hide yes)
			(effects
				(font
					(size 1.016 1.016)
					(thickness 0.1524)
				)
			)
		)
		(duplicate_pad_numbers_are_jumpers no)
		(fp_poly
			(pts
				(arc
					(start 7.3152 0)
					(mid 0 7.3152)
					(end -7.3152 0)
				)
				(arc
					(start -7.3152 -5.9944)
					(mid 0 -13.3096)
					(end 7.3152 -5.9944)
				)
			)
			(stroke
				(width 0)
				(type default)
			)
			(fill no)
			(layer "B.CrtYd")
		)
		(fp_poly
			(pts
				(arc
					(start 7.3152 0)
					(mid 0 7.3152)
					(end -7.3152 0)
				)
				(arc
					(start -7.3152 -5.9944)
					(mid 0 -13.3096)
					(end 7.3152 -5.9944)
				)
			)
			(stroke
				(width 0)
				(type default)
			)
			(fill no)
			(layer "F.CrtYd")
		)
		(fp_poly
			(pts
				(arc
					(start 7.3152 0)
					(mid 0 7.3152)
					(end -7.3152 0)
				)
				(arc
					(start -7.3152 -5.9944)
					(mid 0 -13.3096)
					(end 7.3152 -5.9944)
				)
			)
			(stroke
				(width 0)
				(type default)
			)
			(fill no)
			(layer "B.Fab")
		)
		(fp_poly
			(pts
				(arc
					(start 7.3152 0)
					(mid 0 7.3152)
					(end -7.3152 0)
				)
				(arc
					(start -7.3152 -5.9944)
					(mid 0 -13.3096)
					(end 7.3152 -5.9944)
				)
			)
			(stroke
				(width 0)
				(type default)
			)
			(fill no)
			(layer "F.Fab")
		)
		(pad "1" thru_hole oval
			(at 0 0)
			(size 14.0208 20.0152)
			(drill 0.0254
				(offset 0 -2.9972)
			)
			(layers "*.Cu" "*.Mask")
			(remove_unused_layers no)
			(net "Net_68")
			(clearance -1.002284)
			(thermal_gap 0.1524)
			(padstack
				(mode front_inner_back)
				(layer "Inner"
					(shape custom)
					(size 2.928012 2.928012)
					(options
						(anchor circle)
					)
					(primitives
						(gr_poly
							(pts
								(arc
									(start 4.571746 -2.084324)
									(mid 0.000333 7.430372)
									(end -4.571492 -2.084324)
								)
								(arc
									(start -4.571492 -2.084324)
									(mid -3.570296 -3.611977)
									(end -2.875026 -5.30098)
								)
								(arc
									(start -2.875026 -5.30098)
									(mid 0.000217 -7.43089)
									(end 2.87528 -5.30098)
								)
								(arc
									(start 2.87528 -5.30098)
									(mid 3.570511 -3.611956)
									(end 4.571746 -2.084324)
								)
							)
							(width 0)
							(fill yes)
						)
					)
					(clearance 0.1524)
				)
				(layer "B.Cu"
					(shape oval)
					(size 14.0208 20.0152)
					(offset 0 -2.9972)
					(clearance -1.002284)
				)
			)
		)
		(zone
			(layers "F.Cu" "B.Cu" "In1.Cu" "In2.Cu" "In3.Cu" "In4.Cu" "In5.Cu" "In6.Cu"
				"In7.Cu" "In8.Cu" "In9.Cu" "In10.Cu"
			)
			(hatch none 0.5)
			(connect_pads
				(clearance 0)
			)
			(min_thickness 0.25)
			(keepout
				(tracks not_allowed)
				(vias allowed)
				(pads allowed)
				(copperpour not_allowed)
				(footprints allowed)
			)
			(placement
				(enabled no)
				(sheetname "")
			)
			(fill
				(thermal_gap 0.5)
				(thermal_bridge_width 0.5)
				(island_removal_mode 0)
			)
			(polygon
				(pts
					(arc
						(start 293.18966 -144.200118)
						(mid 300.20006 -151.210518)
						(end 307.21046 -144.200118)
					)
					(arc
						(start 307.21046 -138.205718)
						(mid 300.20006 -131.195318)
						(end 293.18966 -138.205718)
					)
				)
			)
		)
	)
)
